(kicad_pcb
	(version 20241229)
	(generator "pcbnew")
	(generator_version "9.0")
	(general
		(thickness 1.62)
		(legacy_teardrops no)
	)
	(paper "A3")
	(title_block
		(title "COM Express 7 Baseboard")
		(date "2025-02-04")
		(rev "1.1.2")
		(company "Antmicro Ltd")
		(comment 1 "www.antmicro.com")
		(comment 9 "footprints 647-652 of 802")
	)
	(layers
		(0 "F.Cu" signal)
		(4 "In1.Cu" signal)
		(6 "In2.Cu" signal)
		(8 "In3.Cu" signal)
		(10 "In4.Cu" signal)
		(12 "In5.Cu" signal)
		(14 "In6.Cu" signal)
		(2 "B.Cu" signal)
		(9 "F.Adhes" user "F.Adhesive")
		(11 "B.Adhes" user "B.Adhesive")
		(13 "F.Paste" user)
		(15 "B.Paste" user)
		(5 "F.SilkS" user "F.Silkscreen")
		(7 "B.SilkS" user "B.Silkscreen")
		(1 "F.Mask" user)
		(3 "B.Mask" user)
		(17 "Dwgs.User" user "User.Drawings")
		(19 "Cmts.User" user "User.Comments")
		(21 "Eco1.User" user "User.Eco1")
		(23 "Eco2.User" user "User.Eco2")
		(25 "Edge.Cuts" user)
		(27 "Margin" user)
		(31 "F.CrtYd" user "F.Courtyard")
		(29 "B.CrtYd" user "B.Courtyard")
		(35 "F.Fab" user)
		(33 "B.Fab" user)
	)
	(footprint "antmicro-footprints:C_0402_1005Metric"
		(layer "B.Cu")
		(at 142.377 149.258 90)
		(descr "Capacitor SMD 0402")
		(tags "capacitor SMD 0402")
		(property "Reference" "C150"
			(at -1.452 2.323 90)
			(layer "B.SilkS")
			(effects
				(font
					(size 0.7 0.7)
					(thickness 0.15)
				)
				(justify right bottom mirror)
			)
		)
		(property "Value" "C_100n_0402"
			(at -1.022927 -2.155213 90)
			(layer "B.Fab")
			(effects
				(font
					(size 0.7 0.7)
					(thickness 0.15)
				)
				(justify right bottom mirror)
			)
		)
		(property "Datasheet" "https://www.murata.com/products/productdetail?partno=GRM155R61H104KE14%23"
			(at 0 0 90)
			(layer "F.Fab")
			(hide yes)
			(effects
				(font
					(size 1.27 1.27)
					(thickness 0.15)
				)
			)
		)
		(property "Author" "Antmicro"
			(at 291.635 6.881 0)
			(layer "B.Fab")
			(hide yes)
			(effects
				(font
					(size 1 1)
					(thickness 0.15)
				)
				(justify mirror)
			)
		)
		(property "Dielectric" "X5R"
			(at 291.635 6.881 0)
			(layer "B.Fab")
			(hide yes)
			(effects
				(font
					(size 1 1)
					(thickness 0.15)
				)
				(justify mirror)
			)
		)
		(property "License" "Apache-2.0"
			(at 291.635 6.881 0)
			(layer "B.Fab")
			(hide yes)
			(effects
				(font
					(size 1 1)
					(thickness 0.15)
				)
				(justify mirror)
			)
		)
		(property "MPN" "GRM155R61H104KE14D"
			(at 291.635 6.881 0)
			(layer "B.Fab")
			(hide yes)
			(effects
				(font
					(size 1 1)
					(thickness 0.15)
				)
				(justify mirror)
			)
		)
		(property "Manufacturer" "Murata"
			(at 291.635 6.881 0)
			(layer "B.Fab")
			(hide yes)
			(effects
				(font
					(size 1 1)
					(thickness 0.15)
				)
				(justify mirror)
			)
		)
		(property "Public" "False"
			(at 291.635 6.881 0)
			(layer "B.Fab")
			(hide yes)
			(effects
				(font
					(size 1 1)
					(thickness 0.15)
				)
				(justify mirror)
			)
		)
		(property "Val" "100n"
			(at 291.635 6.881 0)
			(layer "B.Fab")
			(hide yes)
			(effects
				(font
					(size 1 1)
					(thickness 0.15)
				)
				(justify mirror)
			)
		)
		(property "Voltage" "50V"
			(at 291.635 6.881 0)
			(layer "B.Fab")
			(hide yes)
			(effects
				(font
					(size 1 1)
					(thickness 0.15)
				)
				(justify mirror)
			)
		)
		(sheetname "KR to SFI #1")
		(sheetfile "kr_sfi.kicad_sch")
		(attr smd)
		(fp_rect
			(start -0.925 0.47)
			(end 0.925 -0.47)
			(stroke
				(width 0.05)
				(type default)
			)
			(fill no)
			(layer "B.CrtYd")
		)
		(fp_line
			(start 0.504 -0.248)
			(end 0.504 0.25)
			(stroke
				(width 0.15)
				(type solid)
			)
			(layer "B.Fab")
		)
		(fp_line
			(start -0.494 -0.248)
			(end 0.504 -0.248)
			(stroke
				(width 0.15)
				(type solid)
			)
			(layer "B.Fab")
		)
		(fp_line
			(start 0.504 0.25)
			(end -0.494 0.25)
			(stroke
				(width 0.15)
				(type solid)
			)
			(layer "B.Fab")
		)
		(fp_line
			(start -0.494 0.25)
			(end -0.494 -0.248)
			(stroke
				(width 0.15)
				(type solid)
			)
			(layer "B.Fab")
		)
		(pad "1" smd roundrect
			(at -0.48 0 90)
			(size 0.59 0.64)
			(layers "B.Cu" "B.Mask" "B.Paste")
			(roundrect_rratio 0.25)
			(net 1 "GND")
			(pintype "passive")
			(teardrops
				(best_length_ratio 0.2)
				(max_length 1)
				(best_width_ratio 0.9)
				(max_width 2)
				(curved_edges yes)
				(filter_ratio 0.9)
				(enabled yes)
				(allow_two_segments yes)
				(prefer_zone_connections yes)
			)
		)
		(pad "2" smd roundrect
			(at 0.48 0 90)
			(size 0.59 0.64)
			(layers "B.Cu" "B.Mask" "B.Paste")
			(roundrect_rratio 0.25)
			(net 78 "+1V8")
			(pintype "passive")
			(teardrops
				(best_length_ratio 0.2)
				(max_length 1)
				(best_width_ratio 0.9)
				(max_width 2)
				(curved_edges yes)
				(filter_ratio 0.9)
				(enabled yes)
				(allow_two_segments yes)
				(prefer_zone_connections yes)
			)
		)
	)
	(footprint "antmicro-footprints:C_0603_1608Metric"
		(layer "B.Cu")
		(at 264.955709 74.06 180)
		(descr "Capacitor SMD 0603")
		(tags "capacitor 0603")
		(property "Reference" "C89"
			(at -1.064999 -1.55 0)
			(layer "B.SilkS")
			(effects
				(font
					(size 0.7 0.7)
					(thickness 0.15)
				)
				(justify left bottom mirror)
			)
		)
		(property "Value" "C_22u_16V_0603"
			(at -1.42757 -1.770288 0)
			(layer "B.Fab")
			(effects
				(font
					(size 0.7 0.7)
					(thickness 0.15)
				)
				(justify left bottom mirror)
			)
		)
		(property "Datasheet" "https://product.samsungsem.com/mlcc/CL10A226MO7JZN.do"
			(at 0 0 180)
			(layer "F.Fab")
			(hide yes)
			(effects
				(font
					(size 1.27 1.27)
					(thickness 0.15)
				)
			)
		)
		(property "Author" "Antmicro"
			(at 529.911418 148.12 0)
			(layer "B.Fab")
			(hide yes)
			(effects
				(font
					(size 1 1)
					(thickness 0.15)
				)
				(justify mirror)
			)
		)
		(property "Dielectric" ""
			(at 529.911418 148.12 0)
			(layer "B.Fab")
			(hide yes)
			(effects
				(font
					(size 1 1)
					(thickness 0.15)
				)
				(justify mirror)
			)
		)
		(property "License" "Apache-2.0"
			(at 529.911418 148.12 0)
			(layer "B.Fab")
			(hide yes)
			(effects
				(font
					(size 1 1)
					(thickness 0.15)
				)
				(justify mirror)
			)
		)
		(property "MPN" "CL10A226MO7JZNC"
			(at 529.911418 148.12 0)
			(layer "B.Fab")
			(hide yes)
			(effects
				(font
					(size 1 1)
					(thickness 0.15)
				)
				(justify mirror)
			)
		)
		(property "Manufacturer" "Samsung Electro-Mechanics"
			(at 529.911418 148.12 0)
			(layer "B.Fab")
			(hide yes)
			(effects
				(font
					(size 1 1)
					(thickness 0.15)
				)
				(justify mirror)
			)
		)
		(property "Public" "False"
			(at 529.911418 148.12 0)
			(layer "B.Fab")
			(hide yes)
			(effects
				(font
					(size 1 1)
					(thickness 0.15)
				)
				(justify mirror)
			)
		)
		(property "Val" "22u"
			(at 529.911418 148.12 0)
			(layer "B.Fab")
			(hide yes)
			(effects
				(font
					(size 1 1)
					(thickness 0.15)
				)
				(justify mirror)
			)
		)
		(property "Voltage" "16V"
			(at 529.911418 148.12 0)
			(layer "B.Fab")
			(hide yes)
			(effects
				(font
					(size 1 1)
					(thickness 0.15)
				)
				(justify mirror)
			)
		)
		(sheetname "Misc")
		(sheetfile "misc.kicad_sch")
		(attr smd)
		(fp_line
			(start 0.15 0.4)
			(end -0.15 0.4)
			(stroke
				(width 0.15)
				(type solid)
			)
			(layer "B.SilkS")
		)
		(fp_line
			(start 0.15 -0.4)
			(end -0.15 -0.4)
			(stroke
				(width 0.15)
				(type solid)
			)
			(layer "B.SilkS")
		)
		(fp_rect
			(start -1.25 0.65)
			(end 1.25 -0.65)
			(stroke
				(width 0.05)
				(type solid)
			)
			(fill no)
			(layer "B.CrtYd")
		)
		(fp_rect
			(start -0.8 0.4)
			(end 0.8 -0.4)
			(stroke
				(width 0.15)
				(type solid)
			)
			(fill no)
			(layer "B.Fab")
		)
		(pad "1" smd roundrect
			(at -0.7 0 180)
			(size 0.8 1)
			(layers "B.Cu" "B.Mask" "B.Paste")
			(roundrect_rratio 0.2)
			(net 1 "GND")
			(pintype "passive")
			(teardrops
				(best_length_ratio 0.2)
				(max_length 1)
				(best_width_ratio 0.9)
				(max_width 2)
				(curved_edges yes)
				(filter_ratio 0.9)
				(enabled yes)
				(allow_two_segments yes)
				(prefer_zone_connections yes)
			)
		)
		(pad "2" smd roundrect
			(at 0.7 0 180)
			(size 0.8 1)
			(layers "B.Cu" "B.Mask" "B.Paste")
			(roundrect_rratio 0.2)
			(net 81 "/Misc/FAN_12V")
			(pintype "passive")
			(teardrops
				(best_length_ratio 0.2)
				(max_length 1)
				(best_width_ratio 0.9)
				(max_width 2)
				(curved_edges yes)
				(filter_ratio 0.9)
				(enabled yes)
				(allow_two_segments yes)
				(prefer_zone_connections yes)
			)
		)
	)
	(footprint "antmicro-footprints:C_0402_1005Metric"
		(layer "B.Cu")
		(at 215.677 131.293 -90)
		(descr "Capacitor SMD 0402")
		(tags "capacitor SMD 0402")
		(property "Reference" "C11"
			(at -1.083 0.477 90)
			(layer "B.SilkS")
			(effects
				(font
					(size 0.7 0.7)
					(thickness 0.15)
				)
				(justify left bottom mirror)
			)
		)
		(property "Value" "C_100n_0402"
			(at -1.022927 -2.155213 90)
			(layer "B.Fab")
			(effects
				(font
					(size 0.7 0.7)
					(thickness 0.15)
				)
				(justify left bottom mirror)
			)
		)
		(property "Datasheet" "https://www.murata.com/products/productdetail?partno=GRM155R61H104KE14%23"
			(at 0 0 270)
			(layer "F.Fab")
			(hide yes)
			(effects
				(font
					(size 1.27 1.27)
					(thickness 0.15)
				)
			)
		)
		(property "Author" "Antmicro"
			(at 84.384 346.97 0)
			(layer "B.Fab")
			(hide yes)
			(effects
				(font
					(size 1 1)
					(thickness 0.15)
				)
				(justify mirror)
			)
		)
		(property "Dielectric" "X5R"
			(at 84.384 346.97 0)
			(layer "B.Fab")
			(hide yes)
			(effects
				(font
					(size 1 1)
					(thickness 0.15)
				)
				(justify mirror)
			)
		)
		(property "License" "Apache-2.0"
			(at 84.384 346.97 0)
			(layer "B.Fab")
			(hide yes)
			(effects
				(font
					(size 1 1)
					(thickness 0.15)
				)
				(justify mirror)
			)
		)
		(property "MPN" "GRM155R61H104KE14D"
			(at 84.384 346.97 0)
			(layer "B.Fab")
			(hide yes)
			(effects
				(font
					(size 1 1)
					(thickness 0.15)
				)
				(justify mirror)
			)
		)
		(property "Manufacturer" "Murata"
			(at 84.384 346.97 0)
			(layer "B.Fab")
			(hide yes)
			(effects
				(font
					(size 1 1)
					(thickness 0.15)
				)
				(justify mirror)
			)
		)
		(property "Public" "False"
			(at 84.384 346.97 0)
			(layer "B.Fab")
			(hide yes)
			(effects
				(font
					(size 1 1)
					(thickness 0.15)
				)
				(justify mirror)
			)
		)
		(property "Val" "100n"
			(at 84.384 346.97 0)
			(layer "B.Fab")
			(hide yes)
			(effects
				(font
					(size 1 1)
					(thickness 0.15)
				)
				(justify mirror)
			)
		)
		(property "Voltage" "50V"
			(at 84.384 346.97 0)
			(layer "B.Fab")
			(hide yes)
			(effects
				(font
					(size 1 1)
					(thickness 0.15)
				)
				(justify mirror)
			)
		)
		(sheetname "PCIe misc")
		(sheetfile "pcie_misc.kicad_sch")
		(attr smd)
		(fp_rect
			(start -0.925 0.47)
			(end 0.925 -0.47)
			(stroke
				(width 0.05)
				(type default)
			)
			(fill no)
			(layer "B.CrtYd")
		)
		(fp_line
			(start -0.494 0.25)
			(end -0.494 -0.248)
			(stroke
				(width 0.15)
				(type solid)
			)
			(layer "B.Fab")
		)
		(fp_line
			(start 0.504 0.25)
			(end -0.494 0.25)
			(stroke
				(width 0.15)
				(type solid)
			)
			(layer "B.Fab")
		)
		(fp_line
			(start -0.494 -0.248)
			(end 0.504 -0.248)
			(stroke
				(width 0.15)
				(type solid)
			)
			(layer "B.Fab")
		)
		(fp_line
			(start 0.504 -0.248)
			(end 0.504 0.25)
			(stroke
				(width 0.15)
				(type solid)
			)
			(layer "B.Fab")
		)
		(pad "1" smd roundrect
			(at -0.48 0 270)
			(size 0.59 0.64)
			(layers "B.Cu" "B.Mask" "B.Paste")
			(roundrect_rratio 0.25)
			(net 1 "GND")
			(pintype "passive")
			(teardrops
				(best_length_ratio 0.2)
				(max_length 1)
				(best_width_ratio 0.9)
				(max_width 2)
				(curved_edges yes)
				(filter_ratio 0.9)
				(enabled yes)
				(allow_two_segments yes)
				(prefer_zone_connections yes)
			)
		)
		(pad "2" smd roundrect
			(at 0.48 0 270)
			(size 0.59 0.64)
			(layers "B.Cu" "B.Mask" "B.Paste")
			(roundrect_rratio 0.25)
			(net 2 "+3V3")
			(pintype "passive")
			(teardrops
				(best_length_ratio 0.2)
				(max_length 1)
				(best_width_ratio 0.9)
				(max_width 2)
				(curved_edges yes)
				(filter_ratio 0.9)
				(enabled yes)
				(allow_two_segments yes)
				(prefer_zone_connections yes)
			)
		)
	)
	(footprint "antmicro-footprints:TP_SMD_0.75mm"
		(layer "B.Cu")
		(at 182.5 170.8 180)
		(property "Reference" "TP35"
			(at 0.45 0.45 0)
			(layer "B.SilkS")
			(effects
				(font
					(size 0.7 0.7)
					(thickness 0.15)
				)
				(justify left top mirror)
			)
		)
		(property "Value" "TP_0.75mm_SMD"
			(at 0 -1.2 0)
			(layer "B.Fab")
			(effects
				(font
					(size 0.7 0.7)
					(thickness 0.15)
				)
				(justify left top mirror)
			)
		)
		(property "Author" "Antmicro"
			(at 372.21 -73.39 90)
			(layer "B.Fab")
			(hide yes)
			(effects
				(font
					(size 1 1)
					(thickness 0.15)
				)
				(justify mirror)
			)
		)
		(property "License" "Apache-2.0"
			(at 372.21 -73.39 90)
			(layer "B.Fab")
			(hide yes)
			(effects
				(font
					(size 1 1)
					(thickness 0.15)
				)
				(justify mirror)
			)
		)
		(property "MPN" ""
			(at 372.21 -73.39 90)
			(layer "B.Fab")
			(hide yes)
			(effects
				(font
					(size 1 1)
					(thickness 0.15)
				)
				(justify mirror)
			)
		)
		(property "Manufacturer" ""
			(at 372.21 -73.39 90)
			(layer "B.Fab")
			(hide yes)
			(effects
				(font
					(size 1 1)
					(thickness 0.15)
				)
				(justify mirror)
			)
		)
		(property "Public" "False"
			(at 372.21 -73.39 90)
			(layer "B.Fab")
			(hide yes)
			(effects
				(font
					(size 1 1)
					(thickness 0.15)
				)
				(justify mirror)
			)
		)
		(sheetname "Com Express 7 MGMT")
		(sheetfile "com_express_7_mgmt.kicad_sch")
		(attr exclude_from_pos_files exclude_from_bom)
		(fp_circle
			(center 0 0)
			(end 0.475 0)
			(stroke
				(width 0.05)
				(type default)
			)
			(fill no)
			(layer "B.CrtYd")
		)
		(pad "1" smd circle
			(at 0 0 180)
			(size 0.75 0.75)
			(layers "B.Cu" "B.Mask")
			(net 297 "Net-(J12D-~{SUS_S3})")
			(pinfunction "1")
			(pintype "passive")
			(teardrops
				(best_length_ratio 0.4)
				(max_length 1)
				(best_width_ratio 0.9)
				(max_width 2)
				(curved_edges yes)
				(filter_ratio 0.9)
				(enabled yes)
				(allow_two_segments yes)
				(prefer_zone_connections yes)
			)
		)
	)
	(footprint "antmicro-footprints:R_0402_1005Metric"
		(layer "B.Cu")
		(at 308.824999 106.15 -90)
		(descr "Resistor SMD 0402")
		(tags "resistor SMD 0402")
		(property "Reference" "R92"
			(at 0.76 -0.475001 90)
			(layer "B.SilkS")
			(effects
				(font
					(size 0.7 0.7)
					(thickness 0.15)
				)
				(justify left bottom mirror)
			)
		)
		(property "Value" "R_10k_0402"
			(at -1.011843 -1.772047 90)
			(layer "B.Fab")
			(effects
				(font
					(size 0.7 0.7)
					(thickness 0.15)
				)
				(justify left bottom mirror)
			)
		)
		(property "Datasheet" "https://www.bourns.com/docs/product-datasheets/cr.pdf"
			(at 0 0 270)
			(layer "F.Fab")
			(hide yes)
			(effects
				(font
					(size 1.27 1.27)
					(thickness 0.15)
				)
			)
		)
		(property "Author" "Antmicro"
			(at 202.674999 414.974999 0)
			(layer "B.Fab")
			(hide yes)
			(effects
				(font
					(size 1 1)
					(thickness 0.15)
				)
				(justify mirror)
			)
		)
		(property "License" "Apache-2.0"
			(at 202.674999 414.974999 0)
			(layer "B.Fab")
			(hide yes)
			(effects
				(font
					(size 1 1)
					(thickness 0.15)
				)
				(justify mirror)
			)
		)
		(property "MPN" "CR0402-FX-1002GLF"
			(at 202.674999 414.974999 0)
			(layer "B.Fab")
			(hide yes)
			(effects
				(font
					(size 1 1)
					(thickness 0.15)
				)
				(justify mirror)
			)
		)
		(property "Manufacturer" "Bourns"
			(at 202.674999 414.974999 0)
			(layer "B.Fab")
			(hide yes)
			(effects
				(font
					(size 1 1)
					(thickness 0.15)
				)
				(justify mirror)
			)
		)
		(property "Public" "False"
			(at 202.674999 414.974999 0)
			(layer "B.Fab")
			(hide yes)
			(effects
				(font
					(size 1 1)
					(thickness 0.15)
				)
				(justify mirror)
			)
		)
		(property "Tolerance" "1%"
			(at 202.674999 414.974999 0)
			(layer "B.Fab")
			(hide yes)
			(effects
				(font
					(size 1 1)
					(thickness 0.15)
				)
				(justify mirror)
			)
		)
		(property "Val" "10k"
			(at 202.674999 414.974999 0)
			(layer "B.Fab")
			(hide yes)
			(effects
				(font
					(size 1 1)
					(thickness 0.15)
				)
				(justify mirror)
			)
		)
		(sheetname "Power")
		(sheetfile "power.kicad_sch")
		(attr smd)
		(fp_rect
			(start -0.925 0.47)
			(end 0.925 -0.47)
			(stroke
				(width 0.05)
				(type default)
			)
			(fill no)
			(layer "B.CrtYd")
		)
		(fp_rect
			(start -0.5 0.25)
			(end 0.5 -0.25)
			(stroke
				(width 0.15)
				(type solid)
			)
			(fill no)
			(layer "B.Fab")
		)
		(pad "1" smd roundrect
			(at -0.48 0 270)
			(size 0.59 0.64)
			(layers "B.Cu" "B.Mask" "B.Paste")
			(roundrect_rratio 0.25)
			(net 1 "GND")
			(pintype "passive")
			(teardrops
				(best_length_ratio 0.2)
				(max_length 1)
				(best_width_ratio 0.9)
				(max_width 2)
				(curved_edges yes)
				(filter_ratio 0.9)
				(enabled yes)
				(allow_two_segments yes)
				(prefer_zone_connections yes)
			)
		)
		(pad "2" smd roundrect
			(at 0.48 0 270)
			(size 0.59 0.64)
			(layers "B.Cu" "B.Mask" "B.Paste")
			(roundrect_rratio 0.25)
			(net 576 "Net-(U19-MODE)")
			(pintype "passive")
			(teardrops
				(best_length_ratio 0.2)
				(max_length 1)
				(best_width_ratio 0.9)
				(max_width 2)
				(curved_edges yes)
				(filter_ratio 0.9)
				(enabled yes)
				(allow_two_segments yes)
				(prefer_zone_connections yes)
			)
		)
	)
	(footprint "antmicro-footprints:Mech_M2_2280_H2.5mm"
		(layer "B.Cu")
		(at 261.75 102.11 90)
		(property "Reference" "A2"
			(at 0 -8.89 90)
			(layer "B.SilkS")
			(hide yes)
			(effects
				(font
					(size 0.7 0.7)
					(thickness 0.15)
				)
				(justify left bottom mirror)
			)
		)
		(property "Value" "Mech_M2_2280_H2.5mm"
			(at 0 -6.857 90)
			(layer "B.Fab")
			(effects
				(font
					(size 0.7 0.7)
					(thickness 0.15)
				)
				(justify left bottom mirror)
			)
		)
		(property "Author" "Antmicro"
			(at 363.86 -159.64 0)
			(layer "B.Fab")
			(hide yes)
			(effects
				(font
					(size 1 1)
					(thickness 0.15)
				)
				(justify mirror)
			)
		)
		(property "License" "Apache-2.0"
			(at 363.86 -159.64 0)
			(layer "B.Fab")
			(hide yes)
			(effects
				(font
					(size 1 1)
					(thickness 0.15)
				)
				(justify mirror)
			)
		)
		(property "MPN" ""
			(at 363.86 -159.64 0)
			(layer "B.Fab")
			(hide yes)
			(effects
				(font
					(size 1 1)
					(thickness 0.15)
				)
				(justify mirror)
			)
		)
		(property "Manufacturer" ""
			(at 363.86 -159.64 0)
			(layer "B.Fab")
			(hide yes)
			(effects
				(font
					(size 1 1)
					(thickness 0.15)
				)
				(justify mirror)
			)
		)
		(property "Public" "False"
			(at 363.86 -159.64 0)
			(layer "B.Fab")
			(hide yes)
			(effects
				(font
					(size 1 1)
					(thickness 0.15)
				)
				(justify mirror)
			)
		)
		(sheetname "M.2 key M #1")
		(sheetfile "m2keym_low.kicad_sch")
		(attr exclude_from_pos_files exclude_from_bom allow_missing_courtyard)
		(fp_rect
			(start -10.922 -0.0508)
			(end 11.0236 -80.0608)
			(stroke
				(width 0.15)
				(type solid)
			)
			(fill no)
			(layer "B.Fab")
		)
	)
)
